FILE_TYPE = MACRO_DRAWING;
SET COLOR_WIRE YELLOW;
SET COLOR_PROP ORANGE;
SET COLOR_DOT WHITE;
SET COLOR_ARC YELLOW;
SET COLOR_BODY GREEN;
SET COLOR_NOTE PURPLE;
SET PROP_DISPLAY VALUE;
SET PAGE_NUMBER P70;
FORCEADD Q_CAP..1
(-8600 3100);
FORCEPROP 1 LAST LOCATION C2514
J 0
(-8550 3200);
DISPLAY 0.489362 (-8550 3200);
PAINT SKYBLUE (-8550 3200);
FORCEPROP 2 LAST $SEC 1
J 0
(-8550 3300);
DISPLAY 0.680851 (-8550 3300);
PAINT MONO (-8550 3300);
DISPLAY INVISIBLE (-8550 3300);
FORCEPROP 2 LAST CDS_SEC 1
J 0
(-8550 3300);
DISPLAY 1.021277 (-8550 3300);
DISPLAY INVISIBLE (-8550 3300);
FORCEPROP 1 LASTPIN (-8600 3200) $PN 1
J 0
(-8590 3180);
DISPLAY 0.489362 (-8590 3180);
FORCEPROP 1 LASTPIN (-8600 3000) $PN 2
J 0
(-8590 2980);
DISPLAY 0.489362 (-8590 2980);
FORCEPROP 1 LAST MATERIAL X6S
J 0
(-8550 3000);
DISPLAY 0.489362 (-8550 3000);
PAINT SKYBLUE (-8550 3000);
FORCEPROP 1 LAST TOLERANCE 20%
J 0
(-8550 3050);
DISPLAY 0.489362 (-8550 3050);
PAINT SKYBLUE (-8550 3050);
FORCEPROP 1 LAST VALUE 22UF
J 0
(-8550 3150);
DISPLAY 0.489362 (-8550 3150);
PAINT SKYBLUE (-8550 3150);
FORCEPROP 1 LAST PART_NUMBER CH622KMEB02
J 0
(-8550 2950);
DISPLAY 0.489362 (-8550 2950);
PAINT SKYBLUE (-8550 2950);
FORCEPROP 1 LAST VOLTAGE 4V
J 0
(-8550 3100);
DISPLAY 0.489362 (-8550 3100);
PAINT SKYBLUE (-8550 3100);
FORCEPROP 1 LAST PACK_TYPE C0402
J 0
(-8550 2900);
DISPLAY 0.489362 (-8550 2900);
PAINT SKYBLUE (-8550 2900);
FORCEPROP 2 LAST CDS_LIB pure_quanta
J 0
(-8600 3100);
PAINT MONO (-8600 3100);
DISPLAY INVISIBLE (-8600 3100);
FORCEPROP 1 LAST PATH I1
J 0
(-8550 3250);
DISPLAY 0.978723 (-8550 3250);
PAINT WHITE (-8550 3250);
DISPLAY INVISIBLE (-8550 3250);
FORCEADD Q_CAP..1
(-7700 3875);
FORCEPROP 1 LAST LOCATION C2518
J 0
(-7650 3975);
DISPLAY 0.489362 (-7650 3975);
PAINT SKYBLUE (-7650 3975);
FORCEPROP 2 LAST $SEC 1
J 0
(-7650 4075);
DISPLAY 0.680851 (-7650 4075);
PAINT MONO (-7650 4075);
DISPLAY INVISIBLE (-7650 4075);
FORCEPROP 2 LAST CDS_SEC 1
J 0
(-7650 4075);
DISPLAY 1.021277 (-7650 4075);
DISPLAY INVISIBLE (-7650 4075);
FORCEPROP 1 LASTPIN (-7700 3975) $PN 1
J 0
(-7690 3955);
DISPLAY 0.489362 (-7690 3955);
FORCEPROP 1 LASTPIN (-7700 3775) $PN 2
J 0
(-7690 3755);
DISPLAY 0.489362 (-7690 3755);
FORCEPROP 1 LAST MATERIAL X6S
J 0
(-7650 3775);
DISPLAY 0.489362 (-7650 3775);
PAINT SKYBLUE (-7650 3775);
FORCEPROP 1 LAST TOLERANCE 20%
J 0
(-7650 3825);
DISPLAY 0.489362 (-7650 3825);
PAINT SKYBLUE (-7650 3825);
FORCEPROP 1 LAST VALUE 22UF
J 0
(-7650 3925);
DISPLAY 0.489362 (-7650 3925);
PAINT SKYBLUE (-7650 3925);
FORCEPROP 1 LAST PART_NUMBER CH622KMEB02
J 0
(-7650 3725);
DISPLAY 0.489362 (-7650 3725);
PAINT SKYBLUE (-7650 3725);
FORCEPROP 1 LAST VOLTAGE 4V
J 0
(-7650 3875);
DISPLAY 0.489362 (-7650 3875);
PAINT SKYBLUE (-7650 3875);
FORCEPROP 1 LAST PACK_TYPE C0402
J 0
(-7650 3675);
DISPLAY 0.489362 (-7650 3675);
PAINT SKYBLUE (-7650 3675);
FORCEPROP 2 LAST CDS_LIB pure_quanta
J 0
(-7700 3875);
PAINT MONO (-7700 3875);
DISPLAY INVISIBLE (-7700 3875);
FORCEPROP 1 LAST PATH I10
J 0
(-7650 4025);
DISPLAY 0.978723 (-7650 4025);
PAINT WHITE (-7650 4025);
DISPLAY INVISIBLE (-7650 4025);
FORCEADD Q_CAP..1
(-7250 3875);
FORCEPROP 1 LAST LOCATION C2520
J 0
(-7200 3975);
DISPLAY 0.489362 (-7200 3975);
PAINT SKYBLUE (-7200 3975);
FORCEPROP 2 LAST $SEC 1
J 0
(-7200 4075);
DISPLAY 0.680851 (-7200 4075);
PAINT MONO (-7200 4075);
DISPLAY INVISIBLE (-7200 4075);
FORCEPROP 2 LAST CDS_SEC 1
J 0
(-7200 4075);
DISPLAY 1.021277 (-7200 4075);
DISPLAY INVISIBLE (-7200 4075);
FORCEPROP 1 LASTPIN (-7250 3975) $PN 1
J 0
(-7240 3955);
DISPLAY 0.489362 (-7240 3955);
FORCEPROP 1 LASTPIN (-7250 3775) $PN 2
J 0
(-7240 3755);
DISPLAY 0.489362 (-7240 3755);
FORCEPROP 1 LAST MATERIAL X6S
J 0
(-7200 3775);
DISPLAY 0.489362 (-7200 3775);
PAINT SKYBLUE (-7200 3775);
FORCEPROP 1 LAST TOLERANCE 20%
J 0
(-7200 3825);
DISPLAY 0.489362 (-7200 3825);
PAINT SKYBLUE (-7200 3825);
FORCEPROP 1 LAST VALUE 22UF
J 0
(-7200 3925);
DISPLAY 0.489362 (-7200 3925);
PAINT SKYBLUE (-7200 3925);
FORCEPROP 1 LAST PART_NUMBER CH622KMEB02
J 0
(-7200 3725);
DISPLAY 0.489362 (-7200 3725);
PAINT SKYBLUE (-7200 3725);
FORCEPROP 1 LAST VOLTAGE 4V
J 0
(-7200 3875);
DISPLAY 0.489362 (-7200 3875);
PAINT SKYBLUE (-7200 3875);
FORCEPROP 1 LAST PACK_TYPE C0402
J 0
(-7200 3675);
DISPLAY 0.489362 (-7200 3675);
PAINT SKYBLUE (-7200 3675);
FORCEPROP 2 LAST CDS_LIB pure_quanta
J 0
(-7250 3875);
PAINT MONO (-7250 3875);
DISPLAY INVISIBLE (-7250 3875);
FORCEPROP 1 LAST PATH I11
J 0
(-7200 4025);
DISPLAY 0.978723 (-7200 4025);
PAINT WHITE (-7200 4025);
DISPLAY INVISIBLE (-7200 4025);
FORCEADD Q_CAP..1
(-6800 3875);
FORCEPROP 1 LAST LOCATION C2521
J 0
(-6750 3975);
DISPLAY 0.489362 (-6750 3975);
PAINT SKYBLUE (-6750 3975);
FORCEPROP 2 LAST $SEC 1
J 0
(-6750 4075);
DISPLAY 0.680851 (-6750 4075);
PAINT MONO (-6750 4075);
DISPLAY INVISIBLE (-6750 4075);
FORCEPROP 2 LAST CDS_SEC 1
J 0
(-6750 4075);
DISPLAY 1.021277 (-6750 4075);
DISPLAY INVISIBLE (-6750 4075);
FORCEPROP 1 LASTPIN (-6800 3975) $PN 1
J 0
(-6790 3955);
DISPLAY 0.489362 (-6790 3955);
FORCEPROP 1 LASTPIN (-6800 3775) $PN 2
J 0
(-6790 3755);
DISPLAY 0.489362 (-6790 3755);
FORCEPROP 1 LAST MATERIAL X6S
J 0
(-6750 3775);
DISPLAY 0.489362 (-6750 3775);
PAINT SKYBLUE (-6750 3775);
FORCEPROP 1 LAST TOLERANCE 20%
J 0
(-6750 3825);
DISPLAY 0.489362 (-6750 3825);
PAINT SKYBLUE (-6750 3825);
FORCEPROP 1 LAST VALUE 22UF
J 0
(-6750 3925);
DISPLAY 0.489362 (-6750 3925);
PAINT SKYBLUE (-6750 3925);
FORCEPROP 1 LAST PART_NUMBER CH622KMEB02
J 0
(-6750 3725);
DISPLAY 0.489362 (-6750 3725);
PAINT SKYBLUE (-6750 3725);
FORCEPROP 1 LAST VOLTAGE 4V
J 0
(-6750 3875);
DISPLAY 0.489362 (-6750 3875);
PAINT SKYBLUE (-6750 3875);
FORCEPROP 1 LAST PACK_TYPE C0402
J 0
(-6750 3675);
DISPLAY 0.489362 (-6750 3675);
PAINT SKYBLUE (-6750 3675);
FORCEPROP 2 LAST CDS_LIB pure_quanta
J 0
(-6800 3875);
PAINT MONO (-6800 3875);
DISPLAY INVISIBLE (-6800 3875);
FORCEPROP 1 LAST PATH I12
J 0
(-6750 4025);
DISPLAY 0.978723 (-6750 4025);
PAINT WHITE (-6750 4025);
DISPLAY INVISIBLE (-6750 4025);
FORCEADD Q_CAP..1
(-6350 3875);
FORCEPROP 1 LAST LOCATION C2522
J 0
(-6300 3975);
DISPLAY 0.489362 (-6300 3975);
PAINT SKYBLUE (-6300 3975);
FORCEPROP 2 LAST $SEC 1
J 0
(-6300 4075);
DISPLAY 0.680851 (-6300 4075);
PAINT MONO (-6300 4075);
DISPLAY INVISIBLE (-6300 4075);
FORCEPROP 2 LAST CDS_SEC 1
J 0
(-6300 4075);
DISPLAY 1.021277 (-6300 4075);
DISPLAY INVISIBLE (-6300 4075);
FORCEPROP 1 LASTPIN (-6350 3975) $PN 1
J 0
(-6340 3955);
DISPLAY 0.489362 (-6340 3955);
FORCEPROP 1 LASTPIN (-6350 3775) $PN 2
J 0
(-6340 3755);
DISPLAY 0.489362 (-6340 3755);
FORCEPROP 1 LAST MATERIAL X6S
J 0
(-6300 3775);
DISPLAY 0.489362 (-6300 3775);
PAINT SKYBLUE (-6300 3775);
FORCEPROP 1 LAST TOLERANCE 20%
J 0
(-6300 3825);
DISPLAY 0.489362 (-6300 3825);
PAINT SKYBLUE (-6300 3825);
FORCEPROP 1 LAST VALUE 22UF
J 0
(-6300 3925);
DISPLAY 0.489362 (-6300 3925);
PAINT SKYBLUE (-6300 3925);
FORCEPROP 1 LAST PART_NUMBER CH622KMEB02
J 0
(-6300 3725);
DISPLAY 0.489362 (-6300 3725);
PAINT SKYBLUE (-6300 3725);
FORCEPROP 1 LAST VOLTAGE 4V
J 0
(-6300 3875);
DISPLAY 0.489362 (-6300 3875);
PAINT SKYBLUE (-6300 3875);
FORCEPROP 1 LAST PACK_TYPE C0402
J 0
(-6300 3675);
DISPLAY 0.489362 (-6300 3675);
PAINT SKYBLUE (-6300 3675);
FORCEPROP 2 LAST CDS_LIB pure_quanta
J 0
(-6350 3875);
PAINT MONO (-6350 3875);
DISPLAY INVISIBLE (-6350 3875);
FORCEPROP 1 LAST PATH I13
J 0
(-6300 4025);
DISPLAY 0.978723 (-6300 4025);
PAINT WHITE (-6300 4025);
DISPLAY INVISIBLE (-6300 4025);
FORCEADD Q_CAP..1
(-5900 3875);
FORCEPROP 1 LAST LOCATION C2523
J 0
(-5850 3975);
DISPLAY 0.489362 (-5850 3975);
PAINT SKYBLUE (-5850 3975);
FORCEPROP 2 LAST $SEC 1
J 0
(-5850 4075);
DISPLAY 0.680851 (-5850 4075);
PAINT MONO (-5850 4075);
DISPLAY INVISIBLE (-5850 4075);
FORCEPROP 2 LAST CDS_SEC 1
J 0
(-5850 4075);
DISPLAY 1.021277 (-5850 4075);
DISPLAY INVISIBLE (-5850 4075);
FORCEPROP 1 LASTPIN (-5900 3975) $PN 1
J 0
(-5890 3955);
DISPLAY 0.489362 (-5890 3955);
FORCEPROP 1 LASTPIN (-5900 3775) $PN 2
J 0
(-5890 3755);
DISPLAY 0.489362 (-5890 3755);
FORCEPROP 1 LAST MATERIAL X6S
J 0
(-5850 3775);
DISPLAY 0.489362 (-5850 3775);
PAINT SKYBLUE (-5850 3775);
FORCEPROP 1 LAST TOLERANCE 20%
J 0
(-5850 3825);
DISPLAY 0.489362 (-5850 3825);
PAINT SKYBLUE (-5850 3825);
FORCEPROP 1 LAST VALUE 22UF
J 0
(-5850 3925);
DISPLAY 0.489362 (-5850 3925);
PAINT SKYBLUE (-5850 3925);
FORCEPROP 1 LAST PART_NUMBER CH622KMEB02
J 0
(-5850 3725);
DISPLAY 0.489362 (-5850 3725);
PAINT SKYBLUE (-5850 3725);
FORCEPROP 1 LAST VOLTAGE 4V
J 0
(-5850 3875);
DISPLAY 0.489362 (-5850 3875);
PAINT SKYBLUE (-5850 3875);
FORCEPROP 1 LAST PACK_TYPE C0402
J 0
(-5850 3675);
DISPLAY 0.489362 (-5850 3675);
PAINT SKYBLUE (-5850 3675);
FORCEPROP 2 LAST CDS_LIB pure_quanta
J 0
(-5900 3875);
PAINT MONO (-5900 3875);
DISPLAY INVISIBLE (-5900 3875);
FORCEPROP 1 LAST PATH I14
J 0
(-5850 4025);
DISPLAY 0.978723 (-5850 4025);
PAINT WHITE (-5850 4025);
DISPLAY INVISIBLE (-5850 4025);
FORCEADD Q_CAP..1
(-5450 3875);
FORCEPROP 1 LAST LOCATION C2524
J 0
(-5400 3975);
DISPLAY 0.489362 (-5400 3975);
PAINT SKYBLUE (-5400 3975);
FORCEPROP 2 LAST $SEC 1
J 0
(-5400 4075);
DISPLAY 0.680851 (-5400 4075);
PAINT MONO (-5400 4075);
DISPLAY INVISIBLE (-5400 4075);
FORCEPROP 2 LAST CDS_SEC 1
J 0
(-5400 4075);
DISPLAY 1.021277 (-5400 4075);
DISPLAY INVISIBLE (-5400 4075);
FORCEPROP 1 LASTPIN (-5450 3975) $PN 1
J 0
(-5440 3955);
DISPLAY 0.489362 (-5440 3955);
FORCEPROP 1 LASTPIN (-5450 3775) $PN 2
J 0
(-5440 3755);
DISPLAY 0.489362 (-5440 3755);
FORCEPROP 1 LAST MATERIAL X6S
J 0
(-5400 3775);
DISPLAY 0.489362 (-5400 3775);
PAINT SKYBLUE (-5400 3775);
FORCEPROP 1 LAST TOLERANCE 20%
J 0
(-5400 3825);
DISPLAY 0.489362 (-5400 3825);
PAINT SKYBLUE (-5400 3825);
FORCEPROP 1 LAST VALUE 22UF
J 0
(-5400 3925);
DISPLAY 0.489362 (-5400 3925);
PAINT SKYBLUE (-5400 3925);
FORCEPROP 1 LAST PART_NUMBER CH622KMEB02
J 0
(-5400 3725);
DISPLAY 0.489362 (-5400 3725);
PAINT SKYBLUE (-5400 3725);
FORCEPROP 1 LAST VOLTAGE 4V
J 0
(-5400 3875);
DISPLAY 0.489362 (-5400 3875);
PAINT SKYBLUE (-5400 3875);
FORCEPROP 1 LAST PACK_TYPE C0402
J 0
(-5400 3675);
DISPLAY 0.489362 (-5400 3675);
PAINT SKYBLUE (-5400 3675);
FORCEPROP 2 LAST CDS_LIB pure_quanta
J 0
(-5450 3875);
PAINT MONO (-5450 3875);
DISPLAY INVISIBLE (-5450 3875);
FORCEPROP 1 LAST PATH I15
J 0
(-5400 4025);
DISPLAY 0.978723 (-5400 4025);
PAINT WHITE (-5400 4025);
DISPLAY INVISIBLE (-5400 4025);
FORCEADD Q_CAP..1
(-5000 3875);
FORCEPROP 1 LAST LOCATION C2525
J 0
(-4950 3975);
DISPLAY 0.489362 (-4950 3975);
PAINT SKYBLUE (-4950 3975);
FORCEPROP 2 LAST $SEC 1
J 0
(-4950 4075);
DISPLAY 0.680851 (-4950 4075);
PAINT MONO (-4950 4075);
DISPLAY INVISIBLE (-4950 4075);
FORCEPROP 2 LAST CDS_SEC 1
J 0
(-4950 4075);
DISPLAY 1.021277 (-4950 4075);
DISPLAY INVISIBLE (-4950 4075);
FORCEPROP 1 LASTPIN (-5000 3975) $PN 1
J 0
(-4990 3955);
DISPLAY 0.489362 (-4990 3955);
FORCEPROP 1 LASTPIN (-5000 3775) $PN 2
J 0
(-4990 3755);
DISPLAY 0.489362 (-4990 3755);
FORCEPROP 1 LAST MATERIAL X6S
J 0
(-4950 3775);
DISPLAY 0.489362 (-4950 3775);
PAINT SKYBLUE (-4950 3775);
FORCEPROP 1 LAST TOLERANCE 20%
J 0
(-4950 3825);
DISPLAY 0.489362 (-4950 3825);
PAINT SKYBLUE (-4950 3825);
FORCEPROP 1 LAST VALUE 22UF
J 0
(-4950 3925);
DISPLAY 0.489362 (-4950 3925);
PAINT SKYBLUE (-4950 3925);
FORCEPROP 1 LAST PART_NUMBER CH622KMEB02
J 0
(-4950 3725);
DISPLAY 0.489362 (-4950 3725);
PAINT SKYBLUE (-4950 3725);
FORCEPROP 1 LAST VOLTAGE 4V
J 0
(-4950 3875);
DISPLAY 0.489362 (-4950 3875);
PAINT SKYBLUE (-4950 3875);
FORCEPROP 1 LAST PACK_TYPE C0402
J 0
(-4950 3675);
DISPLAY 0.489362 (-4950 3675);
PAINT SKYBLUE (-4950 3675);
FORCEPROP 2 LAST CDS_LIB pure_quanta
J 0
(-5000 3875);
PAINT MONO (-5000 3875);
DISPLAY INVISIBLE (-5000 3875);
FORCEPROP 1 LAST PATH I16
J 0
(-4950 4025);
DISPLAY 0.978723 (-4950 4025);
PAINT WHITE (-4950 4025);
DISPLAY INVISIBLE (-4950 4025);
FORCEADD UNIVERSAL_GND..1
(-4600 3500);
FORCEPROP 3 LASTPIN (-4600 3550) SIG_NAME GND\g
J 0
(-4590 3560);
DISPLAY 0.659574 (-4590 3560);
PAINT MONO (-4590 3560);
DISPLAY INVISIBLE (-4590 3560);
FORCEPROP 2 LAST CDS_LIB pure_quanta_power
J 0
(-4600 3500);
PAINT MONO (-4600 3500);
DISPLAY INVISIBLE (-4600 3500);
FORCEPROP 1 LAST PATH I17
J 0
(-4525 3500);
DISPLAY 0.872340 (-4525 3500);
PAINT AQUA (-4525 3500);
DISPLAY INVISIBLE (-4525 3500);
FORCEPROP 1 LAST HDL_POWER GND
J 1
(-4575 3425);
DISPLAY 0.872340 (-4575 3425);
PAINT GREEN (-4575 3425);
DISPLAY INVISIBLE (-4575 3425);
FORCEADD Q_CAP..1
(-4600 3875);
FORCEPROP 1 LAST LOCATION C2526
J 0
(-4550 3975);
DISPLAY 0.489362 (-4550 3975);
PAINT SKYBLUE (-4550 3975);
FORCEPROP 2 LAST $SEC 1
J 0
(-4550 4075);
DISPLAY 0.680851 (-4550 4075);
PAINT MONO (-4550 4075);
DISPLAY INVISIBLE (-4550 4075);
FORCEPROP 2 LAST CDS_SEC 1
J 0
(-4550 4075);
DISPLAY 1.021277 (-4550 4075);
DISPLAY INVISIBLE (-4550 4075);
FORCEPROP 1 LASTPIN (-4600 3975) $PN 1
J 0
(-4590 3955);
DISPLAY 0.489362 (-4590 3955);
FORCEPROP 1 LASTPIN (-4600 3775) $PN 2
J 0
(-4590 3755);
DISPLAY 0.489362 (-4590 3755);
FORCEPROP 1 LAST MATERIAL X6S
J 0
(-4550 3775);
DISPLAY 0.489362 (-4550 3775);
PAINT SKYBLUE (-4550 3775);
FORCEPROP 1 LAST TOLERANCE 20%
J 0
(-4550 3825);
DISPLAY 0.489362 (-4550 3825);
PAINT SKYBLUE (-4550 3825);
FORCEPROP 1 LAST VALUE 22UF
J 0
(-4550 3925);
DISPLAY 0.489362 (-4550 3925);
PAINT SKYBLUE (-4550 3925);
FORCEPROP 1 LAST PART_NUMBER CH622KMEB02
J 0
(-4550 3725);
DISPLAY 0.489362 (-4550 3725);
PAINT SKYBLUE (-4550 3725);
FORCEPROP 1 LAST VOLTAGE 4V
J 0
(-4550 3875);
DISPLAY 0.489362 (-4550 3875);
PAINT SKYBLUE (-4550 3875);
FORCEPROP 1 LAST PACK_TYPE C0402
J 0
(-4550 3675);
DISPLAY 0.489362 (-4550 3675);
PAINT SKYBLUE (-4550 3675);
FORCEPROP 2 LAST CDS_LIB pure_quanta
J 0
(-4600 3875);
PAINT MONO (-4600 3875);
DISPLAY INVISIBLE (-4600 3875);
FORCEPROP 1 LAST PATH I18
J 0
(-4550 4025);
DISPLAY 0.978723 (-4550 4025);
PAINT WHITE (-4550 4025);
DISPLAY INVISIBLE (-4550 4025);
FORCEADD UNIVERSAL_GND..1
(-8150 5125);
FORCEPROP 3 LASTPIN (-8150 5175) SIG_NAME GND\g
J 0
(-8140 5185);
DISPLAY 0.659574 (-8140 5185);
PAINT MONO (-8140 5185);
DISPLAY INVISIBLE (-8140 5185);
FORCEPROP 2 LAST CDS_LIB pure_quanta_power
J 0
(-8150 5125);
PAINT MONO (-8150 5125);
DISPLAY INVISIBLE (-8150 5125);
FORCEPROP 1 LAST PATH I19
J 0
(-8075 5125);
DISPLAY 0.872340 (-8075 5125);
PAINT AQUA (-8075 5125);
DISPLAY INVISIBLE (-8075 5125);
FORCEPROP 1 LAST HDL_POWER GND
J 1
(-8125 5050);
DISPLAY 0.872340 (-8125 5050);
PAINT GREEN (-8125 5050);
DISPLAY INVISIBLE (-8125 5050);
FORCEADD UNIVERSAL_POWER..1
(-8600 3375);
FORCEPROP 3 LASTPIN (-8600 3325) SIG_NAME PVDD18_S5_P0\g
J 0
(-8590 3335);
DISPLAY 0.659574 (-8590 3335);
PAINT MONO (-8590 3335);
DISPLAY INVISIBLE (-8590 3335);
FORCEPROP 1 LAST HDL_POWER PVDD18_S5_P0
J 1
(-8600 3425);
DISPLAY 0.489362 (-8600 3425);
PAINT GREEN (-8600 3425);
FORCEPROP 2 LAST CDS_LIB pure_quanta_power
J 0
(-8600 3375);
DISPLAY INVISIBLE (-8600 3375);
FORCEPROP 1 LAST PATH I2
J 0
(-8550 3400);
DISPLAY 0.872340 (-8550 3400);
PAINT AQUA (-8550 3400);
DISPLAY INVISIBLE (-8550 3400);
FORCEADD Q_CAP..1
(-8150 5500);
FORCEPROP 1 LAST LOCATION C2515
J 0
(-8100 5600);
DISPLAY 0.489362 (-8100 5600);
PAINT SKYBLUE (-8100 5600);
FORCEPROP 2 LAST $SEC 1
J 0
(-8100 5700);
DISPLAY 0.680851 (-8100 5700);
PAINT MONO (-8100 5700);
DISPLAY INVISIBLE (-8100 5700);
FORCEPROP 2 LAST CDS_SEC 1
J 0
(-8100 5700);
DISPLAY 1.021277 (-8100 5700);
DISPLAY INVISIBLE (-8100 5700);
FORCEPROP 1 LASTPIN (-8150 5600) $PN 1
J 0
(-8140 5580);
DISPLAY 0.489362 (-8140 5580);
FORCEPROP 1 LASTPIN (-8150 5400) $PN 2
J 0
(-8140 5380);
DISPLAY 0.489362 (-8140 5380);
FORCEPROP 1 LAST MATERIAL X6S
J 0
(-8100 5400);
DISPLAY 0.489362 (-8100 5400);
PAINT SKYBLUE (-8100 5400);
FORCEPROP 1 LAST TOLERANCE 20%
J 0
(-8100 5450);
DISPLAY 0.489362 (-8100 5450);
PAINT SKYBLUE (-8100 5450);
FORCEPROP 1 LAST VALUE 22UF
J 0
(-8100 5550);
DISPLAY 0.489362 (-8100 5550);
PAINT SKYBLUE (-8100 5550);
FORCEPROP 1 LAST PART_NUMBER CH622KMEB02
J 0
(-8100 5350);
DISPLAY 0.489362 (-8100 5350);
PAINT SKYBLUE (-8100 5350);
FORCEPROP 1 LAST VOLTAGE 4V
J 0
(-8100 5500);
DISPLAY 0.489362 (-8100 5500);
PAINT SKYBLUE (-8100 5500);
FORCEPROP 1 LAST PACK_TYPE C0402
J 0
(-8100 5300);
DISPLAY 0.489362 (-8100 5300);
PAINT SKYBLUE (-8100 5300);
FORCEPROP 2 LAST CDS_LIB pure_quanta
J 0
(-8150 5500);
PAINT MONO (-8150 5500);
DISPLAY INVISIBLE (-8150 5500);
FORCEPROP 1 LAST PATH I20
J 0
(-8100 5650);
DISPLAY 0.978723 (-8100 5650);
PAINT WHITE (-8100 5650);
DISPLAY INVISIBLE (-8100 5650);
FORCEADD Q_CAP..1
(-8600 3875);
FORCEPROP 1 LAST LOCATION C2513
J 0
(-8550 3975);
DISPLAY 0.489362 (-8550 3975);
PAINT SKYBLUE (-8550 3975);
FORCEPROP 2 LAST $SEC 1
J 0
(-8550 4075);
DISPLAY 0.680851 (-8550 4075);
PAINT MONO (-8550 4075);
DISPLAY INVISIBLE (-8550 4075);
FORCEPROP 2 LAST CDS_SEC 1
J 0
(-8550 4075);
DISPLAY 1.021277 (-8550 4075);
DISPLAY INVISIBLE (-8550 4075);
FORCEPROP 1 LASTPIN (-8600 3975) $PN 1
J 0
(-8590 3955);
DISPLAY 0.489362 (-8590 3955);
FORCEPROP 1 LASTPIN (-8600 3775) $PN 2
J 0
(-8590 3755);
DISPLAY 0.489362 (-8590 3755);
FORCEPROP 1 LAST MATERIAL X6S
J 0
(-8550 3775);
DISPLAY 0.489362 (-8550 3775);
PAINT SKYBLUE (-8550 3775);
FORCEPROP 1 LAST TOLERANCE 20%
J 0
(-8550 3825);
DISPLAY 0.489362 (-8550 3825);
PAINT SKYBLUE (-8550 3825);
FORCEPROP 1 LAST VALUE 22UF
J 0
(-8550 3925);
DISPLAY 0.489362 (-8550 3925);
PAINT SKYBLUE (-8550 3925);
FORCEPROP 1 LAST PART_NUMBER CH622KMEB02
J 0
(-8550 3725);
DISPLAY 0.489362 (-8550 3725);
PAINT SKYBLUE (-8550 3725);
FORCEPROP 1 LAST VOLTAGE 4V
J 0
(-8550 3875);
DISPLAY 0.489362 (-8550 3875);
PAINT SKYBLUE (-8550 3875);
FORCEPROP 1 LAST PACK_TYPE C0402
J 0
(-8550 3675);
DISPLAY 0.489362 (-8550 3675);
PAINT SKYBLUE (-8550 3675);
FORCEPROP 2 LAST CDS_LIB pure_quanta
J 0
(-8600 3875);
PAINT MONO (-8600 3875);
DISPLAY INVISIBLE (-8600 3875);
FORCEPROP 1 LAST PATH I3
J 0
(-8550 4025);
DISPLAY 0.978723 (-8550 4025);
PAINT WHITE (-8550 4025);
DISPLAY INVISIBLE (-8550 4025);
FORCEADD UNIVERSAL_POWER..1
(-8600 4150);
FORCEPROP 3 LASTPIN (-8600 4100) SIG_NAME PVDD18_S5_P0\g
J 0
(-8590 4110);
DISPLAY 0.659574 (-8590 4110);
PAINT MONO (-8590 4110);
DISPLAY INVISIBLE (-8590 4110);
FORCEPROP 1 LAST HDL_POWER PVDD18_S5_P0
J 1
(-8600 4200);
DISPLAY 0.489362 (-8600 4200);
PAINT GREEN (-8600 4200);
FORCEPROP 2 LAST CDS_LIB pure_quanta_power
J 0
(-8600 4150);
DISPLAY INVISIBLE (-8600 4150);
FORCEPROP 1 LAST PATH I4
J 0
(-8550 4175);
DISPLAY 0.872340 (-8550 4175);
PAINT AQUA (-8550 4175);
DISPLAY INVISIBLE (-8550 4175);
FORCEADD Q_CAP..1
(-8600 5500);
FORCEPROP 1 LAST LOCATION C2512
J 0
(-8550 5600);
DISPLAY 0.489362 (-8550 5600);
PAINT SKYBLUE (-8550 5600);
FORCEPROP 2 LAST $SEC 1
J 0
(-8550 5700);
DISPLAY 0.680851 (-8550 5700);
PAINT MONO (-8550 5700);
DISPLAY INVISIBLE (-8550 5700);
FORCEPROP 2 LAST CDS_SEC 1
J 0
(-8550 5700);
DISPLAY 1.021277 (-8550 5700);
DISPLAY INVISIBLE (-8550 5700);
FORCEPROP 1 LASTPIN (-8600 5600) $PN 1
J 0
(-8590 5580);
DISPLAY 0.489362 (-8590 5580);
FORCEPROP 1 LASTPIN (-8600 5400) $PN 2
J 0
(-8590 5380);
DISPLAY 0.489362 (-8590 5380);
FORCEPROP 1 LAST MATERIAL X6S
J 0
(-8550 5400);
DISPLAY 0.489362 (-8550 5400);
PAINT SKYBLUE (-8550 5400);
FORCEPROP 1 LAST TOLERANCE 20%
J 0
(-8550 5450);
DISPLAY 0.489362 (-8550 5450);
PAINT SKYBLUE (-8550 5450);
FORCEPROP 1 LAST VALUE 22UF
J 0
(-8550 5550);
DISPLAY 0.489362 (-8550 5550);
PAINT SKYBLUE (-8550 5550);
FORCEPROP 1 LAST PART_NUMBER CH622KMEB02
J 0
(-8550 5350);
DISPLAY 0.489362 (-8550 5350);
PAINT SKYBLUE (-8550 5350);
FORCEPROP 1 LAST VOLTAGE 4V
J 0
(-8550 5500);
DISPLAY 0.489362 (-8550 5500);
PAINT SKYBLUE (-8550 5500);
FORCEPROP 1 LAST PACK_TYPE C0402
J 0
(-8550 5300);
DISPLAY 0.489362 (-8550 5300);
PAINT SKYBLUE (-8550 5300);
FORCEPROP 2 LAST CDS_LIB pure_quanta
J 0
(-8600 5500);
PAINT MONO (-8600 5500);
DISPLAY INVISIBLE (-8600 5500);
FORCEPROP 1 LAST PATH I5
J 0
(-8550 5650);
DISPLAY 0.978723 (-8550 5650);
PAINT WHITE (-8550 5650);
DISPLAY INVISIBLE (-8550 5650);
FORCEADD UNIVERSAL_POWER..1
(-8600 5775);
FORCEPROP 3 LASTPIN (-8600 5725) SIG_NAME PVDD_33_S5\g
J 0
(-8590 5735);
DISPLAY 0.659574 (-8590 5735);
PAINT MONO (-8590 5735);
DISPLAY INVISIBLE (-8590 5735);
FORCEPROP 1 LAST HDL_POWER PVDD_33_S5
J 1
(-8600 5825);
DISPLAY 0.489362 (-8600 5825);
PAINT GREEN (-8600 5825);
FORCEPROP 2 LAST CDS_LIB pure_quanta_power
J 0
(-8600 5775);
DISPLAY INVISIBLE (-8600 5775);
FORCEPROP 1 LAST PATH I6
J 0
(-8550 5800);
DISPLAY 0.872340 (-8550 5800);
PAINT AQUA (-8550 5800);
DISPLAY INVISIBLE (-8550 5800);
FORCEADD UNIVERSAL_GND..1
(-8150 2750);
FORCEPROP 3 LASTPIN (-8150 2800) SIG_NAME GND\g
J 0
(-8140 2810);
DISPLAY 0.659574 (-8140 2810);
PAINT MONO (-8140 2810);
DISPLAY INVISIBLE (-8140 2810);
FORCEPROP 2 LAST CDS_LIB pure_quanta_power
J 0
(-8150 2750);
DISPLAY INVISIBLE (-8150 2750);
FORCEPROP 1 LAST PATH I7
J 0
(-8075 2750);
DISPLAY 0.872340 (-8075 2750);
PAINT AQUA (-8075 2750);
DISPLAY INVISIBLE (-8075 2750);
FORCEPROP 1 LAST HDL_POWER GND
J 1
(-8125 2675);
DISPLAY 0.872340 (-8125 2675);
PAINT GREEN (-8125 2675);
DISPLAY INVISIBLE (-8125 2675);
FORCEADD Q_CAP..1
(-8150 3100);
FORCEPROP 1 LAST LOCATION C2517
J 0
(-8100 3200);
DISPLAY 0.489362 (-8100 3200);
PAINT SKYBLUE (-8100 3200);
FORCEPROP 2 LAST $SEC 1
J 0
(-8100 3300);
DISPLAY 0.680851 (-8100 3300);
PAINT MONO (-8100 3300);
DISPLAY INVISIBLE (-8100 3300);
FORCEPROP 2 LAST CDS_SEC 1
J 0
(-8100 3300);
DISPLAY 1.021277 (-8100 3300);
DISPLAY INVISIBLE (-8100 3300);
FORCEPROP 1 LASTPIN (-8150 3200) $PN 1
J 0
(-8140 3180);
DISPLAY 0.489362 (-8140 3180);
FORCEPROP 1 LASTPIN (-8150 3000) $PN 2
J 0
(-8140 2980);
DISPLAY 0.489362 (-8140 2980);
FORCEPROP 1 LAST MATERIAL X6S
J 0
(-8100 3000);
DISPLAY 0.489362 (-8100 3000);
PAINT SKYBLUE (-8100 3000);
FORCEPROP 1 LAST TOLERANCE 20%
J 0
(-8100 3050);
DISPLAY 0.489362 (-8100 3050);
PAINT SKYBLUE (-8100 3050);
FORCEPROP 1 LAST VALUE 22UF
J 0
(-8100 3150);
DISPLAY 0.489362 (-8100 3150);
PAINT SKYBLUE (-8100 3150);
FORCEPROP 1 LAST PART_NUMBER CH622KMEB02
J 0
(-8100 2950);
DISPLAY 0.489362 (-8100 2950);
PAINT SKYBLUE (-8100 2950);
FORCEPROP 1 LAST VOLTAGE 4V
J 0
(-8100 3100);
DISPLAY 0.489362 (-8100 3100);
PAINT SKYBLUE (-8100 3100);
FORCEPROP 1 LAST PACK_TYPE C0402
J 0
(-8100 2900);
DISPLAY 0.489362 (-8100 2900);
PAINT SKYBLUE (-8100 2900);
FORCEPROP 2 LAST CDS_LIB pure_quanta
J 0
(-8150 3100);
PAINT MONO (-8150 3100);
DISPLAY INVISIBLE (-8150 3100);
FORCEPROP 1 LAST PATH I8
J 0
(-8100 3250);
DISPLAY 0.978723 (-8100 3250);
PAINT WHITE (-8100 3250);
DISPLAY INVISIBLE (-8100 3250);
FORCEADD Q_CAP..1
(-8150 3875);
FORCEPROP 1 LAST LOCATION C2516
J 0
(-8100 3975);
DISPLAY 0.489362 (-8100 3975);
PAINT SKYBLUE (-8100 3975);
FORCEPROP 2 LAST $SEC 1
J 0
(-8100 4075);
DISPLAY 0.680851 (-8100 4075);
PAINT MONO (-8100 4075);
DISPLAY INVISIBLE (-8100 4075);
FORCEPROP 2 LAST CDS_SEC 1
J 0
(-8100 4075);
DISPLAY 1.021277 (-8100 4075);
DISPLAY INVISIBLE (-8100 4075);
FORCEPROP 1 LASTPIN (-8150 3975) $PN 1
J 0
(-8140 3955);
DISPLAY 0.489362 (-8140 3955);
FORCEPROP 1 LASTPIN (-8150 3775) $PN 2
J 0
(-8140 3755);
DISPLAY 0.489362 (-8140 3755);
FORCEPROP 1 LAST MATERIAL X6S
J 0
(-8100 3775);
DISPLAY 0.489362 (-8100 3775);
PAINT SKYBLUE (-8100 3775);
FORCEPROP 1 LAST TOLERANCE 20%
J 0
(-8100 3825);
DISPLAY 0.489362 (-8100 3825);
PAINT SKYBLUE (-8100 3825);
FORCEPROP 1 LAST VALUE 22UF
J 0
(-8100 3925);
DISPLAY 0.489362 (-8100 3925);
PAINT SKYBLUE (-8100 3925);
FORCEPROP 1 LAST PART_NUMBER CH622KMEB02
J 0
(-8100 3725);
DISPLAY 0.489362 (-8100 3725);
PAINT SKYBLUE (-8100 3725);
FORCEPROP 1 LAST VOLTAGE 4V
J 0
(-8100 3875);
DISPLAY 0.489362 (-8100 3875);
PAINT SKYBLUE (-8100 3875);
FORCEPROP 1 LAST PACK_TYPE C0402
J 0
(-8100 3675);
DISPLAY 0.489362 (-8100 3675);
PAINT SKYBLUE (-8100 3675);
FORCEPROP 2 LAST CDS_LIB pure_quanta
J 0
(-8150 3875);
PAINT MONO (-8150 3875);
DISPLAY INVISIBLE (-8150 3875);
FORCEPROP 1 LAST PATH I9
J 0
(-8100 4025);
DISPLAY 0.978723 (-8100 4025);
PAINT WHITE (-8100 4025);
DISPLAY INVISIBLE (-8100 4025);
FORCEADD QUANTA_TITLE_BLOCK_C..1
(0 0);
FORCEPROP 0 LAST CDS_CON_LAST_MODIFIED Fri Mar 11 14:52:45 2022
J 0
(-1885 15);
DISPLAY INVISIBLE (-1885 15);
FORCEPROP 1 LAST CUSTOM_TXT_CDS <CON_LAST_MODIFIED>
J 0
(-1885 15);
DISPLAY 0.978723 (-1885 15);
FORCEPROP 2 LAST CUSTOM_TXT_CDS <XR_PAGE_TITLE>
J 0
(-7890 5250);
DISPLAY 0.638298 (-7890 5250);
PAINT PINK (-7890 5250);
DISPLAY INVISIBLE (-7890 5250);
FORCEPROP 1 LAST CUSTOM_TXT_CDS <NAME_2>
J 0
(-3175 50);
FORCEPROP 1 LAST CUSTOM_TXT_CDS <NAME_1>
J 0
(-3175 175);
FORCEPROP 1 LAST CUSTOM_TXT_CDS <Q_NUMBER>
J 0
(-1403 103);
DISPLAY 1.212766 (-1403 103);
FORCEPROP 1 LAST CUSTOM_TXT_CDS <Q_PROJ>
J 0
(-2382 102);
DISPLAY 1.212766 (-2382 102);
FORCEPROP 1 LAST CUSTOM_TXT_CDS <Q_REV>
J 0
(-184 103);
DISPLAY 1.212766 (-184 103);
FORCEPROP 1 LAST CUSTOM_TXT_CDS <CON_PAGE_NUM> OF <CON_TOTAL_PAGES>
J 0
(-446 18);
DISPLAY 0.978723 (-446 18);
FORCEPROP 1 LAST Q_DEPT BU9
J 1
(-3763 49);
DISPLAY 1.957447 (-3763 49);
PAINT GREEN (-3763 49);
FORCEPROP 1 LAST Q_TITLE CPU0 CAVITY BOT DECOUPLING CAPS 3/3
J 0
(-9366 26);
DISPLAY 2.446809 (-9366 26);
PAINT GREEN (-9366 26);
FORCEPROP 2 LAST PAGE_BORDER TRUE
J 0
(-7890 5250);
DISPLAY 0.638298 (-7890 5250);
PAINT PINK (-7890 5250);
DISPLAY INVISIBLE (-7890 5250);
FORCEPROP 2 LAST CDS_LIB pure_quanta
J 0
(0 0);
DISPLAY INVISIBLE (0 0);
FORCEPROP 1 LAST CDS_LMAN_SYM_OUTLINE -9475,6775,100,-125
J 0
(0 0);
DISPLAY 0.468085 (0 0);
PAINT GREEN (0 0);
DISPLAY INVISIBLE (0 0);
FORCEPROP 1 LAST COMMENT_BODY TRUE
J 0
(12 -13);
DISPLAY 0.978723 (12 -13);
PAINT GREEN (12 -13);
DISPLAY INVISIBLE (12 -13);
FORCEPROP 2 LAST CDS_XR_PAGE_TITLE CR-70 : @T6G_MB_LIB.T6G(SCH_1):PAGE70
J 0
(-7890 5250);
DISPLAY 0.638298 (-7890 5250);
PAINT PINK (-7890 5250);
DISPLAY INVISIBLE (-7890 5250);
WIRE 16 -1 (-8150 5675)(-8600 5675);
WIRE 16 -1 (-8150 5600)(-8150 5675);
WIRE 16 -1 (-8600 5675)(-8600 5725);
WIRE 16 -1 (-8600 5675)(-8600 5600);
WIRE 16 -1 (-8150 5275)(-8600 5275);
WIRE 16 -1 (-8150 5275)(-8150 5400);
WIRE 16 -1 (-8150 5175)(-8150 5275);
WIRE 16 -1 (-8600 5275)(-8600 5400);
WIRE 16 -1 (-4600 3975)(-4600 4050);
WIRE 16 -1 (-4600 4050)(-5000 4050);
WIRE 16 -1 (-5000 4050)(-5000 3975);
WIRE 16 -1 (-5000 4050)(-5450 4050);
WIRE 16 -1 (-5450 3975)(-5450 4050);
WIRE 16 -1 (-5450 4050)(-5900 4050);
WIRE 16 -1 (-5900 3975)(-5900 4050);
WIRE 16 -1 (-5900 4050)(-6350 4050);
WIRE 16 -1 (-6350 4050)(-6350 3975);
WIRE 16 -1 (-6350 4050)(-6800 4050);
WIRE 16 -1 (-6800 3975)(-6800 4050);
WIRE 16 -1 (-6800 4050)(-7250 4050);
WIRE 16 -1 (-7250 3975)(-7250 4050);
WIRE 16 -1 (-7250 4050)(-7700 4050);
WIRE 16 -1 (-7700 4050)(-7700 3975);
WIRE 16 -1 (-7700 4050)(-8150 4050);
WIRE 16 -1 (-8150 4050)(-8600 4050);
WIRE 16 -1 (-8150 3975)(-8150 4050);
WIRE 16 -1 (-8600 4050)(-8600 4100);
WIRE 16 -1 (-8600 4050)(-8600 3975);
WIRE 16 -1 (-8150 3650)(-8600 3650);
WIRE 16 -1 (-7700 3650)(-8150 3650);
WIRE 16 -1 (-8150 3650)(-8150 3775);
WIRE 16 -1 (-8600 3650)(-8600 3775);
WIRE 16 -1 (-7250 3650)(-7700 3650);
WIRE 16 -1 (-7700 3650)(-7700 3775);
WIRE 16 -1 (-6800 3650)(-7250 3650);
WIRE 16 -1 (-7250 3650)(-7250 3775);
WIRE 16 -1 (-6350 3650)(-6800 3650);
WIRE 16 -1 (-6800 3650)(-6800 3775);
WIRE 16 -1 (-5900 3650)(-6350 3650);
WIRE 16 -1 (-6350 3650)(-6350 3775);
WIRE 16 -1 (-5450 3650)(-5900 3650);
WIRE 16 -1 (-5900 3650)(-5900 3775);
WIRE 16 -1 (-5000 3650)(-5450 3650);
WIRE 16 -1 (-5450 3650)(-5450 3775);
WIRE 16 -1 (-4600 3650)(-5000 3650);
WIRE 16 -1 (-5000 3650)(-5000 3775);
WIRE 16 -1 (-4600 3650)(-4600 3775);
WIRE 16 -1 (-4600 3550)(-4600 3650);
WIRE 16 -1 (-8150 3275)(-8600 3275);
WIRE 16 -1 (-8150 3200)(-8150 3275);
WIRE 16 -1 (-8600 3275)(-8600 3325);
WIRE 16 -1 (-8600 3275)(-8600 3200);
WIRE 16 -1 (-8150 2875)(-8600 2875);
WIRE 16 -1 (-8150 2875)(-8150 3000);
WIRE 16 -1 (-8150 2800)(-8150 2875);
WIRE 16 -1 (-8600 2875)(-8600 3000);
WIRE 16 3135 (-8825 5000)(-4900 5000);
WIRE 16 3135 (-8825 5000)(-8825 6275);
WIRE 16 3135 (-4900 5000)(-4900 6275);
WIRE 16 3135 (-8825 6275)(-4900 6275);
WIRE 16 3135 (-8825 2575)(-4075 2575);
WIRE 16 3135 (-8825 2575)(-8825 4700);
WIRE 16 3135 (-4075 2575)(-4075 4700);
WIRE 16 3135 (-8825 4700)(-4075 4700);
DOT 1 (-8150 5275);
DOT 1 (-4600 3650);
DOT 1 (-5000 4050);
DOT 1 (-5000 3650);
DOT 1 (-5450 4050);
DOT 1 (-5450 3650);
DOT 1 (-5900 4050);
DOT 1 (-5900 3650);
DOT 1 (-6350 4050);
DOT 1 (-6350 3650);
DOT 1 (-6800 4050);
DOT 1 (-6800 3650);
DOT 1 (-7250 4050);
DOT 1 (-7250 3650);
DOT 1 (-7700 4050);
DOT 1 (-7700 3650);
DOT 1 (-8150 4050);
DOT 1 (-8150 3650);
DOT 1 (-8150 2875);
DOT 1 (-8600 5675);
DOT 1 (-8600 4050);
DOT 1 (-8600 3275);
FORCENOTE
10
(-4650 4125) 0;
DISPLAY LEFT (-4650 4125);
DISPLAY 1.021277 (-4650 4125);
PAINT SKYBLUE (-4650 4125);
FORCENOTE
5
(-6825 4125) 0;
DISPLAY LEFT (-6825 4125);
DISPLAY 1.021277 (-6825 4125);
PAINT SKYBLUE (-6825 4125);
FORCENOTE
PVDD33_S5: 2PCS 22UF ON BOT
(-8625 6000) 0;
DISPLAY LEFT (-8625 6000);
DISPLAY 2.510638 (-8625 6000);
PAINT WHITE (-8625 6000);
FORCENOTE
PVDD18_S5_P0: 12PCS 22UF ON BOT
(-8675 4475) 0;
DISPLAY LEFT (-8675 4475);
DISPLAY 2.510638 (-8675 4475);
PAINT WHITE (-8675 4475);
QUIT
